# T6G (Grand Teton) — schematic netlist excerpt (pin names and nets, part order shuffled) for the footprints in the layout excerpt that follows; sources: Cadence DE-HDL packaged netlist, KiCad conversion of 04192023_DAF0TMB3IC0_F0TG_MB_C_brd_V02_OCP.brd

C1797  Q_CAP  0.1UF 25V 10% X7R  pkg 0402  page 268 : A = PDB_PRSNT_R_N ; B = GND
PC326_2  Q_CAP  0.1UF 25V 10% X7R  pkg 0402  page 215 : A = SW_P12V_AUX_PVDDCR_SOC_P1_FLT ; B = GND

(kicad_pcb
	(version 20260206)
	(generator "pcbnew")
	(generator_version "10.0")
	(general
		(thickness 1.6)
		(legacy_teardrops no)
	)
	(paper "A4")
	(title_block
		(title "04192023_DAF0TMB3IC0_F0TG_MB_C_brd_V02_OCP.brd")
		(comment 1 "Grand Teton / footprints 2254-2255 of 8354")
	)
	(layers
		(0 "F.Cu" signal "TOP")
		(4 "In1.Cu" signal "GND")
		(6 "In2.Cu" signal "IN1")
		(8 "In3.Cu" signal "GND1")
		(10 "In4.Cu" signal "IN2")
		(12 "In5.Cu" signal "GND2")
		(14 "In6.Cu" signal "IN3")
		(16 "In7.Cu" signal "GND3")
		(18 "In8.Cu" signal "VCC")
		(20 "In9.Cu" signal "VCC1")
		(22 "In10.Cu" signal "GND4")
		(24 "In11.Cu" signal "IN4")
		(26 "In12.Cu" signal "GND5")
		(28 "In13.Cu" signal "IN5")
		(30 "In14.Cu" signal "GND6")
		(32 "In15.Cu" signal "IN6")
		(34 "In16.Cu" signal "GND7")
		(2 "B.Cu" signal "BOTTOM")
		(9 "F.Adhes" user "F.Adhesive")
		(11 "B.Adhes" user "B.Adhesive")
		(13 "F.Paste" user "Package Geometry/Pastemask Top")
		(15 "B.Paste" user "Package Geometry/Pastemask Bottom")
		(5 "F.SilkS" user "Ref Des/Silkscreen Top")
		(7 "B.SilkS" user "Ref Des/Silkscreen Bottom")
		(1 "F.Mask" user "Board Geometry/Soldermask Top")
		(3 "B.Mask" user "Board Geometry/Soldermask Bottom")
		(17 "Dwgs.User" user "User.Drawings")
		(19 "Cmts.User" user "User.Comments")
		(21 "Eco1.User" user "User.Eco1")
		(23 "Eco2.User" user "User.Eco2")
		(25 "Edge.Cuts" user "Board Geometry/Outline")
		(27 "Margin" user)
		(31 "F.CrtYd" user "Package Geometry/Place Bound Top")
		(29 "B.CrtYd" user "Package Geometry/Place Bound Bottom")
		(35 "F.Fab" user "Ref Des/Assembly Top")
		(33 "B.Fab" user "Ref Des/Assembly Bottom")
	)
	(footprint ""
		(layer "F.Cu")
		(at 270.312134 -421.23868 90)
		(property "Reference" "C1797"
			(at 0 0 90)
			(layer "F.SilkS")
			(hide yes)
			(effects
				(font
					(size 1.27 1.27)
				)
			)
		)
		(property "Value" ""
			(at 0 0 90)
			(layer "F.Fab")
			(effects
				(font
					(size 1.27 1.27)
				)
			)
		)
		(duplicate_pad_numbers_are_jumpers no)
		(fp_line
			(start 0.7874 -0.4064)
			(end 0.7874 0.4064)
			(stroke
				(width 0.1524)
				(type default)
			)
			(layer "F.SilkS")
		)
		(fp_line
			(start -0.7874 -0.4064)
			(end 0.7874 -0.4064)
			(stroke
				(width 0.1524)
				(type default)
			)
			(layer "F.SilkS")
		)
		(fp_line
			(start 0.7874 0.4064)
			(end -0.7874 0.4064)
			(stroke
				(width 0.1524)
				(type default)
			)
			(layer "F.SilkS")
		)
		(fp_line
			(start -0.7874 0.4064)
			(end -0.7874 -0.4064)
			(stroke
				(width 0.1524)
				(type default)
			)
			(layer "F.SilkS")
		)
		(fp_line
			(start -0.12065 -0.305054)
			(end -0.12065 -0.2794)
			(stroke
				(width 0.1)
				(type default)
			)
			(layer "F.Fab")
		)
		(fp_line
			(start -0.67945 -0.305054)
			(end -0.12065 -0.305054)
			(stroke
				(width 0.1)
				(type default)
			)
			(layer "F.Fab")
		)
		(fp_line
			(start 0.67945 -0.3048)
			(end 0.67945 0.3048)
			(stroke
				(width 0.1)
				(type default)
			)
			(layer "F.Fab")
		)
		(fp_line
			(start 0.12065 -0.3048)
			(end 0.67945 -0.3048)
			(stroke
				(width 0.1)
				(type default)
			)
			(layer "F.Fab")
		)
		(fp_line
			(start 0.12065 -0.2794)
			(end 0.12065 -0.3048)
			(stroke
				(width 0.1)
				(type default)
			)
			(layer "F.Fab")
		)
		(fp_line
			(start -0.12065 -0.2794)
			(end 0.12065 -0.2794)
			(stroke
				(width 0.1)
				(type default)
			)
			(layer "F.Fab")
		)
		(fp_line
			(start 0.120396 0.2794)
			(end -0.12065 0.2794)
			(stroke
				(width 0.1)
				(type default)
			)
			(layer "F.Fab")
		)
		(fp_line
			(start -0.12065 0.2794)
			(end -0.12065 0.3048)
			(stroke
				(width 0.1)
				(type default)
			)
			(layer "F.Fab")
		)
		(fp_line
			(start 0.67945 0.3048)
			(end 0.120396 0.3048)
			(stroke
				(width 0.1)
				(type default)
			)
			(layer "F.Fab")
		)
		(fp_line
			(start 0.120396 0.3048)
			(end 0.120396 0.2794)
			(stroke
				(width 0.1)
				(type default)
			)
			(layer "F.Fab")
		)
		(fp_line
			(start -0.12065 0.3048)
			(end -0.67945 0.3048)
			(stroke
				(width 0.1)
				(type default)
			)
			(layer "F.Fab")
		)
		(fp_line
			(start -0.67945 0.3048)
			(end -0.67945 -0.305054)
			(stroke
				(width 0.1)
				(type default)
			)
			(layer "F.Fab")
		)
		(pad "1" smd circle
			(at -0.40005 0 90)
			(size 0 0)
			(layers "F.Cu" "F.Mask" "F.Paste")
			(net "PDB_PRSNT_R_N")
		)
		(pad "2" smd circle
			(at 0.40005 0 90)
			(size 0 0)
			(layers "F.Cu" "F.Mask" "F.Paste")
			(net "GND")
		)
	)
	(footprint ""
		(layer "F.Cu")
		(at 119.349774 -165.109398 90)
		(property "Reference" "PC326_2"
			(at 0 0 90)
			(layer "F.SilkS")
			(hide yes)
			(effects
				(font
					(size 1.27 1.27)
				)
			)
		)
		(property "Value" ""
			(at 0 0 90)
			(layer "F.Fab")
			(effects
				(font
					(size 1.27 1.27)
				)
			)
		)
		(duplicate_pad_numbers_are_jumpers no)
		(fp_line
			(start 0.7874 -0.4064)
			(end 0.7874 0.4064)
			(stroke
				(width 0.1524)
				(type default)
			)
			(layer "F.SilkS")
		)
		(fp_line
			(start -0.7874 -0.4064)
			(end 0.7874 -0.4064)
			(stroke
				(width 0.1524)
				(type default)
			)
			(layer "F.SilkS")
		)
		(fp_line
			(start 0.7874 0.4064)
			(end -0.7874 0.4064)
			(stroke
				(width 0.1524)
				(type default)
			)
			(layer "F.SilkS")
		)
		(fp_line
			(start -0.7874 0.4064)
			(end -0.7874 -0.4064)
			(stroke
				(width 0.1524)
				(type default)
			)
			(layer "F.SilkS")
		)
		(fp_line
			(start -0.12065 -0.305054)
			(end -0.12065 -0.2794)
			(stroke
				(width 0.1)
				(type default)
			)
			(layer "F.Fab")
		)
		(fp_line
			(start -0.67945 -0.305054)
			(end -0.12065 -0.305054)
			(stroke
				(width 0.1)
				(type default)
			)
			(layer "F.Fab")
		)
		(fp_line
			(start 0.67945 -0.3048)
			(end 0.67945 0.3048)
			(stroke
				(width 0.1)
				(type default)
			)
			(layer "F.Fab")
		)
		(fp_line
			(start 0.12065 -0.3048)
			(end 0.67945 -0.3048)
			(stroke
				(width 0.1)
				(type default)
			)
			(layer "F.Fab")
		)
		(fp_line
			(start 0.12065 -0.2794)
			(end 0.12065 -0.3048)
			(stroke
				(width 0.1)
				(type default)
			)
			(layer "F.Fab")
		)
		(fp_line
			(start -0.12065 -0.2794)
			(end 0.12065 -0.2794)
			(stroke
				(width 0.1)
				(type default)
			)
			(layer "F.Fab")
		)
		(fp_line
			(start 0.120396 0.2794)
			(end -0.12065 0.2794)
			(stroke
				(width 0.1)
				(type default)
			)
			(layer "F.Fab")
		)
		(fp_line
			(start -0.12065 0.2794)
			(end -0.12065 0.3048)
			(stroke
				(width 0.1)
				(type default)
			)
			(layer "F.Fab")
		)
		(fp_line
			(start 0.67945 0.3048)
			(end 0.120396 0.3048)
			(stroke
				(width 0.1)
				(type default)
			)
			(layer "F.Fab")
		)
		(fp_line
			(start 0.120396 0.3048)
			(end 0.120396 0.2794)
			(stroke
				(width 0.1)
				(type default)
			)
			(layer "F.Fab")
		)
		(fp_line
			(start -0.12065 0.3048)
			(end -0.67945 0.3048)
			(stroke
				(width 0.1)
				(type default)
			)
			(layer "F.Fab")
		)
		(fp_line
			(start -0.67945 0.3048)
			(end -0.67945 -0.305054)
			(stroke
				(width 0.1)
				(type default)
			)
			(layer "F.Fab")
		)
		(pad "1" smd circle
			(at -0.40005 0 90)
			(size 0 0)
			(layers "F.Cu" "F.Mask" "F.Paste")
			(net "SW_P12V_AUX_PVDDCR_SOC_P1_FLT")
		)
		(pad "2" smd circle
			(at 0.40005 0 90)
			(size 0 0)
			(layers "F.Cu" "F.Mask" "F.Paste")
			(net "GND")
		)
	)
)
